(kicad_pcb
	(version 20241229)
	(generator "pcbnew")
	(generator_version "9.0")
	(general
		(thickness 1.61)
		(legacy_teardrops no)
	)
	(paper "A3")
	(title_block
		(title "RDIMM DDR5 Tester")
		(date "2026-05-21")
		(rev "2.2.0")
		(company "Antmicro")
		(comment 9 "footprints 114-117 of 796")
	)
	(layers
		(0 "F.Cu" signal)
		(4 "In1.Cu" power)
		(6 "In2.Cu" mixed)
		(8 "In3.Cu" power)
		(10 "In4.Cu" mixed)
		(12 "In5.Cu" power)
		(14 "In6.Cu" mixed)
		(16 "In7.Cu" power)
		(18 "In8.Cu" power)
		(20 "In9.Cu" mixed)
		(22 "In10.Cu" power)
		(2 "B.Cu" signal)
		(9 "F.Adhes" user "F.Adhesive")
		(11 "B.Adhes" user "B.Adhesive")
		(13 "F.Paste" user)
		(15 "B.Paste" user)
		(5 "F.SilkS" user "F.Silkscreen")
		(7 "B.SilkS" user "B.Silkscreen")
		(1 "F.Mask" user)
		(3 "B.Mask" user)
		(17 "Dwgs.User" user "User.Drawings")
		(19 "Cmts.User" user "User.Comments")
		(21 "Eco1.User" user "User.Eco1")
		(23 "Eco2.User" user "User.Eco2")
		(25 "Edge.Cuts" user)
		(27 "Margin" user)
		(31 "F.CrtYd" user "F.Courtyard")
		(29 "B.CrtYd" user "B.Courtyard")
		(35 "F.Fab" user)
		(33 "B.Fab" user)
	)
	(footprint "antmicro-footprints:R_0402_1005Metric"
		(layer "F.Cu")
		(at 114.806 173.322 -90)
		(descr "Resistor SMD 0402")
		(tags "resistor SMD 0402")
		(property "Reference" "R38"
			(at -3.05 -0.43 90)
			(layer "F.SilkS")
			(effects
				(font
					(size 0.7 0.7)
					(thickness 0.15)
				)
				(justify right bottom)
			)
		)
		(property "Value" "R_0R_0402"
			(at -1.011843 1.772047 90)
			(layer "F.Fab")
			(effects
				(font
					(size 0.7 0.7)
					(thickness 0.15)
				)
				(justify right bottom)
			)
		)
		(property "Datasheet" "https://industrial.panasonic.com/cdbs/www-data/pdf/RDA0000/AOA0000C301.pdf"
			(at 0 0 270)
			(layer "F.Fab")
			(hide yes)
			(effects
				(font
					(size 1.27 1.27)
					(thickness 0.15)
				)
			)
		)
		(property "MPN" "ERJ2GE0R00X"
			(at 0 0 270)
			(unlocked yes)
			(layer "F.Fab")
			(hide yes)
			(effects
				(font
					(size 1 1)
					(thickness 0.15)
				)
			)
		)
		(property "Manufacturer" "Panasonic"
			(at 0 0 270)
			(unlocked yes)
			(layer "F.Fab")
			(hide yes)
			(effects
				(font
					(size 1 1)
					(thickness 0.15)
				)
			)
		)
		(property "License" "Apache-2.0"
			(at 0 0 270)
			(unlocked yes)
			(layer "F.Fab")
			(hide yes)
			(effects
				(font
					(size 1 1)
					(thickness 0.15)
				)
			)
		)
		(property "Author" "Antmicro"
			(at 0 0 270)
			(unlocked yes)
			(layer "F.Fab")
			(hide yes)
			(effects
				(font
					(size 1 1)
					(thickness 0.15)
				)
			)
		)
		(property "Val" "0R"
			(at 0 0 270)
			(unlocked yes)
			(layer "F.Fab")
			(hide yes)
			(effects
				(font
					(size 1 1)
					(thickness 0.15)
				)
			)
		)
		(property "Tolerance" "~"
			(at 0 0 270)
			(unlocked yes)
			(layer "F.Fab")
			(hide yes)
			(effects
				(font
					(size 1 1)
					(thickness 0.15)
				)
			)
		)
		(property "Current" "1A"
			(at 0 0 270)
			(unlocked yes)
			(layer "F.Fab")
			(hide yes)
			(effects
				(font
					(size 1 1)
					(thickness 0.15)
				)
			)
		)
		(sheetname "/HDMI + SD Card/")
		(sheetfile "hdmi-sd-card.kicad_sch")
		(attr smd)
		(fp_rect
			(start -0.925 -0.47)
			(end 0.925 0.47)
			(stroke
				(width 0.05)
				(type default)
			)
			(fill no)
			(layer "F.CrtYd")
		)
		(fp_rect
			(start -0.5 -0.25)
			(end 0.5 0.25)
			(stroke
				(width 0.15)
				(type solid)
			)
			(fill no)
			(layer "F.Fab")
		)
		(fp_text user "License: Apache-2.0"
			(at -0.95 5.169 270)
			(layer "F.Fab")
			(effects
				(font
					(size 0.7 0.7)
					(thickness 0.15)
				)
				(justify left bottom)
			)
		)
		(fp_text user "${REFERENCE}"
			(at -0.95 3.168 270)
			(layer "F.Fab")
			(effects
				(font
					(size 0.7 0.7)
					(thickness 0.15)
				)
				(justify left bottom)
			)
		)
		(fp_text user "Author: Antmicro"
			(at -0.95 4.169 270)
			(layer "F.Fab")
			(effects
				(font
					(size 0.7 0.7)
					(thickness 0.15)
				)
				(justify left bottom)
			)
		)
		(pad "1" smd roundrect
			(at -0.48 0 270)
			(size 0.59 0.64)
			(layers "F.Cu" "F.Mask" "F.Paste")
			(roundrect_rratio 0.25)
			(net 530 "Net-(U38-HPD_SNK)")
			(pintype "passive")
		)
		(pad "2" smd roundrect
			(at 0.48 0 270)
			(size 0.59 0.64)
			(layers "F.Cu" "F.Mask" "F.Paste")
			(roundrect_rratio 0.25)
			(net 605 "/HDMI + SD Card/HDMI0.HPD")
			(pintype "passive")
		)
	)
	(footprint "antmicro-footprints:MicroSD_Wurth_693071020811"
		(layer "F.Cu")
		(at 105.584 160.865 -90)
		(descr "SMT MICRO SD CARD CONNECTOR")
		(property "Reference" "J5"
			(at 8.685 -3.991 0)
			(layer "F.SilkS")
			(effects
				(font
					(size 0.7 0.7)
					(thickness 0.15)
				)
				(justify left bottom)
			)
		)
		(property "Value" "MicroSD_693071020811"
			(at 0 8.9 90)
			(layer "F.Fab")
			(effects
				(font
					(size 0.7 0.7)
					(thickness 0.15)
				)
				(justify right bottom)
			)
		)
		(property "Datasheet" "https://www.we-online.com/catalog/datasheet/693071020811.pdf"
			(at 0 0 90)
			(layer "F.Fab")
			(hide yes)
			(effects
				(font
					(size 1.27 1.27)
					(thickness 0.15)
				)
			)
		)
		(property "Manufacturer" "Würth Elektronik"
			(at 0 0 270)
			(unlocked yes)
			(layer "F.Fab")
			(hide yes)
			(effects
				(font
					(size 1 1)
					(thickness 0.15)
				)
			)
		)
		(property "MPN" "693071020811"
			(at 0 0 270)
			(unlocked yes)
			(layer "F.Fab")
			(hide yes)
			(effects
				(font
					(size 1 1)
					(thickness 0.15)
				)
			)
		)
		(property "Author" "Antmicro"
			(at 0 0 270)
			(unlocked yes)
			(layer "F.Fab")
			(hide yes)
			(effects
				(font
					(size 1 1)
					(thickness 0.15)
				)
			)
		)
		(property "License" "Apache-2.0"
			(at 0 0 270)
			(unlocked yes)
			(layer "F.Fab")
			(hide yes)
			(effects
				(font
					(size 1 1)
					(thickness 0.15)
				)
			)
		)
		(sheetname "/HDMI + SD Card/")
		(sheetfile "hdmi-sd-card.kicad_sch")
		(attr smd)
		(fp_line
			(start -7.35 1.432)
			(end -7.35 -5.267)
			(stroke
				(width 0.15)
				(type solid)
			)
			(layer "F.SilkS")
		)
		(fp_line
			(start 7.35 1.432)
			(end 7.35 -5.267)
			(stroke
				(width 0.15)
				(type solid)
			)
			(layer "F.SilkS")
		)
		(fp_line
			(start 6.201 -7.148)
			(end 2.801 -7.148)
			(stroke
				(width 0.15)
				(type solid)
			)
			(layer "F.SilkS")
		)
		(fp_circle
			(center 2.85 -7.9)
			(end 2.9 -7.9)
			(stroke
				(width 0.15)
				(type solid)
			)
			(fill yes)
			(layer "F.SilkS")
		)
		(fp_line
			(start -7.55 7.7)
			(end -7.55 4.55)
			(stroke
				(width 0.05)
				(type solid)
			)
			(layer "F.CrtYd")
		)
		(fp_line
			(start 7.5 7.7)
			(end -7.55 7.7)
			(stroke
				(width 0.05)
				(type solid)
			)
			(layer "F.CrtYd")
		)
		(fp_line
			(start 7.5 7.7)
			(end 7.5 4.55)
			(stroke
				(width 0.05)
				(type solid)
			)
			(layer "F.CrtYd")
		)
		(fp_line
			(start -8.7 4.55)
			(end -7.55 4.55)
			(stroke
				(width 0.05)
				(type solid)
			)
			(layer "F.CrtYd")
		)
		(fp_line
			(start -8.7 4.55)
			(end -8.7 1.6)
			(stroke
				(width 0.05)
				(type solid)
			)
			(layer "F.CrtYd")
		)
		(fp_line
			(start 8.7 4.55)
			(end 7.5 4.55)
			(stroke
				(width 0.05)
				(type solid)
			)
			(layer "F.CrtYd")
		)
		(fp_line
			(start 8.7 4.55)
			(end 8.7 1.6)
			(stroke
				(width 0.05)
				(type solid)
			)
			(layer "F.CrtYd")
		)
		(fp_line
			(start -7.55 1.6)
			(end -8.7 1.6)
			(stroke
				(width 0.05)
				(type solid)
			)
			(layer "F.CrtYd")
		)
		(fp_line
			(start 7.5 1.6)
			(end 8.7 1.6)
			(stroke
				(width 0.05)
				(type solid)
			)
			(layer "F.CrtYd")
		)
		(fp_line
			(start 7.5 1.6)
			(end 7.5 -5.45)
			(stroke
				(width 0.05)
				(type solid)
			)
			(layer "F.CrtYd")
		)
		(fp_line
			(start -7.55 -5.45)
			(end -7.55 1.6)
			(stroke
				(width 0.05)
				(type solid)
			)
			(layer "F.CrtYd")
		)
		(fp_line
			(start -7.55 -5.45)
			(end -9.1 -5.45)
			(stroke
				(width 0.05)
				(type solid)
			)
			(layer "F.CrtYd")
		)
		(fp_line
			(start 7.5 -5.45)
			(end 8.4 -5.45)
			(stroke
				(width 0.05)
				(type solid)
			)
			(layer "F.CrtYd")
		)
		(fp_line
			(start -9.1 -7.6)
			(end -9.1 -5.45)
			(stroke
				(width 0.05)
				(type solid)
			)
			(layer "F.CrtYd")
		)
		(fp_line
			(start -9.1 -7.6)
			(end -7.05 -7.6)
			(stroke
				(width 0.05)
				(type solid)
			)
			(layer "F.CrtYd")
		)
		(fp_line
			(start 2.75 -7.6)
			(end 2.75 -8.7)
			(stroke
				(width 0.05)
				(type solid)
			)
			(layer "F.CrtYd")
		)
		(fp_line
			(start 8.4 -7.6)
			(end 8.4 -5.45)
			(stroke
				(width 0.05)
				(type solid)
			)
			(layer "F.CrtYd")
		)
		(fp_line
			(start 8.4 -7.6)
			(end 2.75 -7.6)
			(stroke
				(width 0.05)
				(type solid)
			)
			(layer "F.CrtYd")
		)
		(fp_line
			(start -7.05 -8.7)
			(end -7.05 -7.6)
			(stroke
				(width 0.05)
				(type solid)
			)
			(layer "F.CrtYd")
		)
		(fp_line
			(start -7.05 -8.7)
			(end 2.75 -8.7)
			(stroke
				(width 0.05)
				(type solid)
			)
			(layer "F.CrtYd")
		)
		(fp_line
			(start -7.35 7.502)
			(end 7.35 7.502)
			(stroke
				(width 0.15)
				(type solid)
			)
			(layer "F.Fab")
		)
		(fp_line
			(start 7.35 7.353)
			(end 7.35 -7.148)
			(stroke
				(width 0.15)
				(type solid)
			)
			(layer "F.Fab")
		)
		(fp_line
			(start -7.35 -7.148)
			(end -7.35 7.353)
			(stroke
				(width 0.15)
				(type solid)
			)
			(layer "F.Fab")
		)
		(fp_line
			(start 7.35 -7.148)
			(end -7.35 -7.148)
			(stroke
				(width 0.15)
				(type solid)
			)
			(layer "F.Fab")
		)
		(fp_text user "Author: Antmicro"
			(at -9.1 13.501 270)
			(layer "F.Fab")
			(effects
				(font
					(size 0.7 0.7)
					(thickness 0.15)
				)
				(justify left bottom)
			)
		)
		(fp_text user "${REFERENCE}"
			(at -9.1 15.901 270)
			(layer "F.Fab")
			(effects
				(font
					(size 0.7 0.7)
					(thickness 0.15)
				)
				(justify left bottom)
			)
		)
		(fp_text user "License: Apache-2.0"
			(at -9.1 14.701 270)
			(layer "F.Fab")
			(effects
				(font
					(size 0.7 0.7)
					(thickness 0.15)
				)
				(justify left bottom)
			)
		)
		(pad "" np_thru_hole circle
			(at -4.95 3.485 270)
			(size 1 1)
			(drill 1)
			(layers "*.Cu" "*.Mask")
		)
		(pad "" np_thru_hole oval
			(at 3.05 3.485 270)
			(size 1.7 1)
			(drill oval 1.7 1)
			(layers "*.Cu" "*.Mask")
		)
		(pad "1" smd rect
			(at 2.25 -7.57 270)
			(size 0.7 1.9)
			(layers "F.Cu" "F.Mask" "F.Paste")
			(net 606 "/HDMI + SD Card/SD_DAT2")
			(pinfunction "DAT2")
			(pintype "bidirectional")
		)
		(pad "2" smd rect
			(at 1.15 -7.57 270)
			(size 0.7 1.9)
			(layers "F.Cu" "F.Mask" "F.Paste")
			(net 607 "/HDMI + SD Card/SD_DAT3")
			(pinfunction "DAT3/CD")
			(pintype "bidirectional")
		)
		(pad "3" smd rect
			(at 0.05 -7.57 270)
			(size 0.7 1.9)
			(layers "F.Cu" "F.Mask" "F.Paste")
			(net 608 "/HDMI + SD Card/SD_CMD")
			(pinfunction "CMD")
			(pintype "input")
		)
		(pad "4" smd rect
			(at -1.05 -7.57 270)
			(size 0.7 1.9)
			(layers "F.Cu" "F.Mask" "F.Paste")
			(net 151 "+3V3")
			(pinfunction "VDD")
			(pintype "power_in")
		)
		(pad "5" smd rect
			(at -2.15 -7.57 270)
			(size 0.7 1.9)
			(layers "F.Cu" "F.Mask" "F.Paste")
			(net 609 "/HDMI + SD Card/SD_CLK")
			(pinfunction "CLK")
			(pintype "input")
		)
		(pad "6" smd rect
			(at -3.25 -7.57 270)
			(size 0.7 1.9)
			(layers "F.Cu" "F.Mask" "F.Paste")
			(net 1 "GND")
			(pinfunction "VSS")
			(pintype "passive")
		)
		(pad "7" smd rect
			(at -4.35 -7.57 270)
			(size 0.7 1.9)
			(layers "F.Cu" "F.Mask" "F.Paste")
			(net 611 "/HDMI + SD Card/SD_DAT0")
			(pinfunction "DAT0")
			(pintype "input")
		)
		(pad "8" smd rect
			(at -5.45 -7.57 270)
			(size 0.7 1.9)
			(layers "F.Cu" "F.Mask" "F.Paste")
			(net 612 "/HDMI + SD Card/SD_DAT1")
			(pinfunction "DAT1")
			(pintype "input")
		)
		(pad "9" smd rect
			(at -6.55 -7.57 270)
			(size 0.7 1.9)
			(layers "F.Cu" "F.Mask" "F.Paste")
			(net 249 "Net-(J5-CD_SW1)")
			(pinfunction "CD_SW1")
			(pintype "passive")
		)
		(pad "SH" smd rect
			(at -8.1 -6.515 270)
			(size 1.7 1.8)
			(layers "F.Cu" "F.Mask" "F.Paste")
			(net 1 "GND")
			(pinfunction "SH")
			(pintype "passive")
		)
		(pad "SH" smd rect
			(at -7.85 3.08 270)
			(size 1.4 2.6)
			(layers "F.Cu" "F.Mask" "F.Paste")
			(net 1 "GND")
			(pinfunction "SH")
			(pintype "passive")
		)
		(pad "SH" smd rect
			(at 7.4 -6.515 270)
			(size 1.7 1.8)
			(layers "F.Cu" "F.Mask" "F.Paste")
			(net 1 "GND")
			(pinfunction "SH")
			(pintype "passive")
		)
		(pad "SH" smd rect
			(at 7.85 3.08 270)
			(size 1.4 2.6)
			(layers "F.Cu" "F.Mask" "F.Paste")
			(net 1 "GND")
			(pinfunction "SH")
			(pintype "passive")
		)
	)
	(footprint "antmicro-footprints:C_0603_1608Metric"
		(layer "F.Cu")
		(at 242.8 114.7)
		(descr "Capacitor SMD 0603")
		(tags "capacitor 0603")
		(property "Reference" "C7"
			(at -2.8 0.26 0)
			(layer "F.SilkS")
			(effects
				(font
					(size 0.7 0.7)
					(thickness 0.15)
				)
				(justify left bottom)
			)
		)
		(property "Value" "C_10u_25V_0603"
			(at -1.42757 1.770288 0)
			(layer "F.Fab")
			(effects
				(font
					(size 0.7 0.7)
					(thickness 0.15)
				)
				(justify left bottom)
			)
		)
		(property "Datasheet" "https://product.tdk.com/en/search/capacitor/ceramic/mlcc/info?part_no=C1608X5R1E106M080AC"
			(at 0 0 0)
			(layer "F.Fab")
			(hide yes)
			(effects
				(font
					(size 1.27 1.27)
					(thickness 0.15)
				)
			)
		)
		(property "MPN" "C1608X5R1E106M080AC"
			(at 0 0 0)
			(unlocked yes)
			(layer "F.Fab")
			(hide yes)
			(effects
				(font
					(size 1 1)
					(thickness 0.15)
				)
			)
		)
		(property "Manufacturer" "TDK"
			(at 0 0 0)
			(unlocked yes)
			(layer "F.Fab")
			(hide yes)
			(effects
				(font
					(size 1 1)
					(thickness 0.15)
				)
			)
		)
		(property "License" "Apache-2.0"
			(at 0 0 0)
			(unlocked yes)
			(layer "F.Fab")
			(hide yes)
			(effects
				(font
					(size 1 1)
					(thickness 0.15)
				)
			)
		)
		(property "Author" "Antmicro"
			(at 0 0 0)
			(unlocked yes)
			(layer "F.Fab")
			(hide yes)
			(effects
				(font
					(size 1 1)
					(thickness 0.15)
				)
			)
		)
		(property "Val" "10u"
			(at 0 0 0)
			(unlocked yes)
			(layer "F.Fab")
			(hide yes)
			(effects
				(font
					(size 1 1)
					(thickness 0.15)
				)
			)
		)
		(property "Voltage" "25V"
			(at 0 0 0)
			(unlocked yes)
			(layer "F.Fab")
			(hide yes)
			(effects
				(font
					(size 1 1)
					(thickness 0.15)
				)
			)
		)
		(property "Dielectric" ""
			(at 0 0 0)
			(unlocked yes)
			(layer "F.Fab")
			(hide yes)
			(effects
				(font
					(size 1 1)
					(thickness 0.15)
				)
			)
		)
		(sheetname "/DDR5 RDIMM/")
		(sheetfile "ddr5-rdimm.kicad_sch")
		(attr smd)
		(fp_line
			(start -0.15 -0.4)
			(end 0.15 -0.4)
			(stroke
				(width 0.15)
				(type solid)
			)
			(layer "F.SilkS")
		)
		(fp_line
			(start -0.15 0.4)
			(end 0.15 0.4)
			(stroke
				(width 0.15)
				(type solid)
			)
			(layer "F.SilkS")
		)
		(fp_rect
			(start -1.25 -0.65)
			(end 1.25 0.65)
			(stroke
				(width 0.05)
				(type solid)
			)
			(fill no)
			(layer "F.CrtYd")
		)
		(fp_rect
			(start -0.8 -0.4)
			(end 0.8 0.4)
			(stroke
				(width 0.15)
				(type solid)
			)
			(fill no)
			(layer "F.Fab")
		)
		(fp_text user "${REFERENCE}"
			(at -1.682 3.895 0)
			(layer "F.Fab")
			(effects
				(font
					(size 0.7 0.7)
					(thickness 0.15)
				)
				(justify left bottom)
			)
		)
		(fp_text user "Author: Antmicro"
			(at -1.682 4.894 0)
			(layer "F.Fab")
			(effects
				(font
					(size 0.7 0.7)
					(thickness 0.15)
				)
				(justify left bottom)
			)
		)
		(fp_text user "License: Apache-2.0"
			(at -1.682 5.895 0)
			(layer "F.Fab")
			(effects
				(font
					(size 0.7 0.7)
					(thickness 0.15)
				)
				(justify left bottom)
			)
		)
		(pad "1" smd roundrect
			(at -0.7 0)
			(size 0.8 1)
			(layers "F.Cu" "F.Mask" "F.Paste")
			(roundrect_rratio 0.2)
			(net 1 "GND")
			(pintype "passive")
		)
		(pad "2" smd roundrect
			(at 0.7 0)
			(size 0.8 1)
			(layers "F.Cu" "F.Mask" "F.Paste")
			(roundrect_rratio 0.2)
			(net 802 "/DDR5 RDIMM/VIN_BULK")
			(pintype "passive")
		)
	)
	(footprint "antmicro-footprints:MP_NPTH_Drill3mm"
		(layer "F.Cu")
		(at 262 187)
		(property "Reference" "MP3"
			(at 0 -1.8 0)
			(layer "F.SilkS")
			(hide yes)
			(effects
				(font
					(size 0.7 0.7)
					(thickness 0.15)
				)
				(justify left bottom)
			)
		)
		(property "Value" "MP_NPTH_Drill3mm"
			(at 0 2.4 0)
			(layer "F.Fab")
			(effects
				(font
					(size 0.7 0.7)
					(thickness 0.15)
				)
				(justify left bottom)
			)
		)
		(sheetfile "data-center-rdimm-ddr5-tester.kicad_sch")
		(attr board_only exclude_from_pos_files exclude_from_bom)
		(fp_circle
			(center 0 0)
			(end 1.6 0)
			(stroke
				(width 0.05)
				(type default)
			)
			(fill no)
			(layer "F.CrtYd")
		)
		(fp_text user "${REFERENCE}"
			(at 0 4.749 0)
			(layer "F.Fab")
			(effects
				(font
					(size 0.7 0.7)
					(thickness 0.15)
				)
				(justify left bottom)
			)
		)
		(fp_text user "Author: Antmicro"
			(at 0 5.95 0)
			(layer "F.Fab")
			(effects
				(font
					(size 0.7 0.7)
					(thickness 0.15)
				)
				(justify left bottom)
			)
		)
		(fp_text user "License: Apache-2.0"
			(at 0 7.15 0)
			(layer "F.Fab")
			(effects
				(font
					(size 0.7 0.7)
					(thickness 0.15)
				)
				(justify left bottom)
			)
		)
		(pad "" np_thru_hole circle
			(at 0 0)
			(size 3 3)
			(drill 3)
			(layers "*.Cu" "*.Mask")
		)
	)
)
